(kicad_pcb
	(version 20260206)
	(generator "pcbnew")
	(generator_version "10.0")
	(general
		(thickness 1.6)
		(legacy_teardrops no)
	)
	(paper "A4")
	(title_block
		(title "v1-chassis-manager — T6M_CM_d_v01_1031_1645.brd")
		(comment 1 "Open CloudServer (Microsoft) / footprint 1507 of 2512 (U2), pads 715-830 of 1283")
	)
	(layers
		(0 "F.Cu" signal "TOP")
		(4 "In1.Cu" signal "GND1")
		(6 "In2.Cu" signal "IN1")
		(8 "In3.Cu" signal "VCC1")
		(10 "In4.Cu" signal "VCC2")
		(12 "In5.Cu" signal "GND2")
		(14 "In6.Cu" signal "IN2")
		(16 "In7.Cu" signal "IN3")
		(18 "In8.Cu" signal "GND3")
		(2 "B.Cu" signal "BOTTOM")
		(9 "F.Adhes" user "F.Adhesive")
		(11 "B.Adhes" user "B.Adhesive")
		(13 "F.Paste" user "Package Geometry/Pastemask Top")
		(15 "B.Paste" user "Package Geometry/Pastemask Bottom")
		(5 "F.SilkS" user "Ref Des/Silkscreen Top")
		(7 "B.SilkS" user "Ref Des/Silkscreen Bottom")
		(1 "F.Mask" user "Board Geometry/Soldermask Top")
		(3 "B.Mask" user "Board Geometry/Soldermask Bottom")
		(17 "Dwgs.User" user "User.Drawings")
		(19 "Cmts.User" user "User.Comments")
		(21 "Eco1.User" user "User.Eco1")
		(23 "Eco2.User" user "User.Eco2")
		(25 "Edge.Cuts" user "Board Geometry/Outline")
		(27 "Margin" user)
		(31 "F.CrtYd" user "Package Geometry/Place Bound Top")
		(29 "B.CrtYd" user "Package Geometry/Place Bound Bottom")
		(35 "F.Fab" user "Ref Des/Assembly Top")
		(33 "B.Fab" user "Ref Des/Assembly Bottom")
	)
	(footprint ""
		(layer "F.Cu")
		(at 58.000646 -75.799442)
		(property "Reference" "U2"
			(at -20.2438 -18.364708 0)
			(unlocked yes)
			(layer "F.SilkS")
			(effects
				(font
					(size 1.6002 1.1938)
					(thickness 0.1524)
				)
				(justify left)
			)
		)
		(property "Value" ""
			(at 0 0 0)
			(layer "F.Fab")
			(effects
				(font
					(size 1.27 1.27)
				)
			)
		)
		(duplicate_pad_numbers_are_jumpers no)
		(pad "BK15" smd circle
			(at -9.41324 11.063224)
			(size 0.3048 0.3048)
			(layers "F.Cu" "F.Mask" "F.Paste")
			(net "GND")
		)
		(pad "BK17" smd circle
			(at -8.391652 11.063224)
			(size 0.3048 0.3048)
			(layers "F.Cu" "F.Mask" "F.Paste")
			(net "GND")
		)
		(pad "BK18" smd circle
			(at -7.689342 11.013694)
			(size 0.3048 0.3048)
			(layers "F.Cu" "F.Mask" "F.Paste")
			(net "GND")
		)
		(pad "BK19" smd circle
			(at -7.011162 11.204448)
			(size 0.3048 0.3048)
			(layers "F.Cu" "F.Mask" "F.Paste")
			(net "GND")
		)
		(pad "BK21" smd circle
			(at -6.311138 11.204448)
			(size 0.3048 0.3048)
			(layers "F.Cu" "F.Mask" "F.Paste")
			(net "GND")
		)
		(pad "BK22" smd circle
			(at -5.617718 11.073638)
			(size 0.3048 0.3048)
			(layers "F.Cu" "F.Mask" "F.Paste")
			(net "GND")
		)
		(pad "BK24" smd circle
			(at -4.910328 11.063224)
			(size 0.3048 0.3048)
			(layers "F.Cu" "F.Mask" "F.Paste")
			(net "GND")
		)
		(pad "BK26" smd circle
			(at -3.88874 11.063224)
			(size 0.3048 0.3048)
			(layers "F.Cu" "F.Mask" "F.Paste")
			(net "GND")
		)
		(pad "BK27" smd circle
			(at -3.18643 11.013694)
			(size 0.3048 0.3048)
			(layers "F.Cu" "F.Mask" "F.Paste")
			(net "GND")
		)
		(pad "BK28" smd circle
			(at -2.50825 11.204448)
			(size 0.3048 0.3048)
			(layers "F.Cu" "F.Mask" "F.Paste")
			(net "GND")
		)
		(pad "BK30" smd circle
			(at -1.808226 11.204448)
			(size 0.3048 0.3048)
			(layers "F.Cu" "F.Mask" "F.Paste")
			(net "GND")
		)
		(pad "BK31" smd circle
			(at -1.114806 11.073638)
			(size 0.3048 0.3048)
			(layers "F.Cu" "F.Mask" "F.Paste")
			(net "GND")
		)
		(pad "BK32" smd circle
			(at -0.407416 11.063224)
			(size 0.3048 0.3048)
			(layers "F.Cu" "F.Mask" "F.Paste")
			(net "PV_VDDR_NODE1")
		)
		(pad "BK35" smd circle
			(at 0.614172 11.063224)
			(size 0.3048 0.3048)
			(layers "F.Cu" "F.Mask" "F.Paste")
			(net "PV_VDDR_NODE1")
		)
		(pad "BK36" smd circle
			(at 1.316482 11.013694)
			(size 0.3048 0.3048)
			(layers "F.Cu" "F.Mask" "F.Paste")
			(net "GND")
		)
		(pad "BK37" smd circle
			(at 1.994662 11.204448)
			(size 0.3048 0.3048)
			(layers "F.Cu" "F.Mask" "F.Paste")
			(net "PV_VDDR_NODE1")
		)
		(pad "BK39" smd circle
			(at 2.694686 11.204448)
			(size 0.3048 0.3048)
			(layers "F.Cu" "F.Mask" "F.Paste")
			(net "PV_VDDR_NODE1")
		)
		(pad "BK40" smd circle
			(at 3.388106 11.073638)
			(size 0.3048 0.3048)
			(layers "F.Cu" "F.Mask" "F.Paste")
			(net "M_DDR3_NODE1_MA0")
		)
		(pad "BK42" smd circle
			(at 4.095496 11.063224)
			(size 0.3048 0.3048)
			(layers "F.Cu" "F.Mask" "F.Paste")
			(net "GND")
		)
		(pad "BK44" smd circle
			(at 5.117084 11.063224)
			(size 0.3048 0.3048)
			(layers "F.Cu" "F.Mask" "F.Paste")
			(net "PV_VDDR_NODE1")
		)
		(pad "BK45" smd circle
			(at 5.819394 11.013694)
			(size 0.3048 0.3048)
			(layers "F.Cu" "F.Mask" "F.Paste")
			(net "M_DDR3_NODE1_CKE1")
		)
		(pad "BK46" smd circle
			(at 6.497574 11.204448)
			(size 0.3048 0.3048)
			(layers "F.Cu" "F.Mask" "F.Paste")
			(net "PV_VDDR_NODE1")
		)
		(pad "BK48" smd circle
			(at 7.197598 11.204448)
			(size 0.3048 0.3048)
			(layers "F.Cu" "F.Mask" "F.Paste")
			(net "GND")
		)
		(pad "BK49" smd circle
			(at 7.891018 11.080496)
			(size 0.3048 0.3048)
			(layers "F.Cu" "F.Mask" "F.Paste")
			(net "M_DDR3_NODE1_ECC7")
		)
		(pad "BK51" smd circle
			(at 8.598408 11.063224)
			(size 0.3048 0.3048)
			(layers "F.Cu" "F.Mask" "F.Paste")
			(net "M_DDR3_NODE1_ECC2")
		)
		(pad "BK53" smd circle
			(at 9.619996 11.063224)
			(size 0.3048 0.3048)
			(layers "F.Cu" "F.Mask" "F.Paste")
			(net "GND")
		)
		(pad "BK54" smd circle
			(at 10.322306 11.013694)
			(size 0.3048 0.3048)
			(layers "F.Cu" "F.Mask" "F.Paste")
			(net "GND")
		)
		(pad "BK56" smd circle
			(at 11.000486 11.204448)
			(size 0.3048 0.3048)
			(layers "F.Cu" "F.Mask" "F.Paste")
			(net "GND")
		)
		(pad "BK57" smd circle
			(at 11.70051 11.204448)
			(size 0.3048 0.3048)
			(layers "F.Cu" "F.Mask" "F.Paste")
			(net "GND")
		)
		(pad "BK58" smd circle
			(at 12.39393 11.080496)
			(size 0.3048 0.3048)
			(layers "F.Cu" "F.Mask" "F.Paste")
			(net "GND")
		)
		(pad "BK60" smd circle
			(at 13.101574 11.063224)
			(size 0.3048 0.3048)
			(layers "F.Cu" "F.Mask" "F.Paste")
			(net "GND")
		)
		(pad "BK62" smd circle
			(at 14.485366 11.485372)
			(size 0.4064 0.4064)
			(layers "F.Cu" "F.Mask" "F.Paste")
			(net "GND")
		)
		(pad "BK64" smd circle
			(at 15.298166 11.485372)
			(size 0.4064 0.4064)
			(layers "F.Cu" "F.Mask" "F.Paste")
			(net "GND")
		)
		(pad "BK66" smd circle
			(at 16.110966 11.485372)
			(size 0.4064 0.4064)
			(layers "F.Cu" "F.Mask" "F.Paste")
			(net "GND")
		)
		(pad "BL7" smd circle
			(at -13.405358 11.542522)
			(size 0.3048 0.3048)
			(layers "F.Cu" "F.Mask" "F.Paste")
			(net "TP_CPU_NODE1_RP0_PERP1")
		)
		(pad "BL8" smd circle
			(at -12.725654 11.751564)
			(size 0.3048 0.3048)
			(layers "F.Cu" "F.Mask" "F.Paste")
			(net "GND")
		)
		(pad "BL10" smd circle
			(at -11.611102 11.900916)
			(size 0.3048 0.3048)
			(layers "F.Cu" "F.Mask" "F.Paste")
			(net "GND")
		)
		(pad "BL12" smd circle
			(at -10.722102 11.900916)
			(size 0.3048 0.3048)
			(layers "F.Cu" "F.Mask" "F.Paste")
			(net "GND")
		)
		(pad "BL14" smd circle
			(at -9.570974 11.794744)
			(size 0.3048 0.3048)
			(layers "F.Cu" "F.Mask" "F.Paste")
			(net "M1_DQ_NODE1_DQ14")
		)
		(pad "BL16" smd circle
			(at -8.902446 11.542522)
			(size 0.3048 0.3048)
			(layers "F.Cu" "F.Mask" "F.Paste")
			(net "GND")
		)
		(pad "BL17" smd circle
			(at -8.222742 11.751564)
			(size 0.3048 0.3048)
			(layers "F.Cu" "F.Mask" "F.Paste")
			(net "M1_DQ_NODE1_DQ15")
		)
		(pad "BL19" smd circle
			(at -7.10819 11.900916)
			(size 0.3048 0.3048)
			(layers "F.Cu" "F.Mask" "F.Paste")
			(net "M1_DQ_NODE1_DQ9")
		)
		(pad "BL21" smd circle
			(at -6.21919 11.900916)
			(size 0.3048 0.3048)
			(layers "F.Cu" "F.Mask" "F.Paste")
			(net "GND")
		)
		(pad "BL23" smd circle
			(at -5.068062 11.794744)
			(size 0.3048 0.3048)
			(layers "F.Cu" "F.Mask" "F.Paste")
			(net "M1_DQ_NODE1_DQ30")
		)
		(pad "BL25" smd circle
			(at -4.399534 11.542522)
			(size 0.3048 0.3048)
			(layers "F.Cu" "F.Mask" "F.Paste")
			(net "GND")
		)
		(pad "BL26" smd circle
			(at -3.71983 11.751564)
			(size 0.3048 0.3048)
			(layers "F.Cu" "F.Mask" "F.Paste")
			(net "M1_DQ_NODE1_DQ31")
		)
		(pad "BL28" smd circle
			(at -2.605278 11.900916)
			(size 0.3048 0.3048)
			(layers "F.Cu" "F.Mask" "F.Paste")
			(net "M1_DQ_NODE1_DQ29")
		)
		(pad "BL30" smd circle
			(at -1.716278 11.900916)
			(size 0.3048 0.3048)
			(layers "F.Cu" "F.Mask" "F.Paste")
			(net "GND")
		)
		(pad "BL32" smd circle
			(at -0.56515 11.794744)
			(size 0.3048 0.3048)
			(layers "F.Cu" "F.Mask" "F.Paste")
			(net "M_DDR3_NODE1_MA12")
		)
		(pad "BL34" smd circle
			(at 0.103378 11.542522)
			(size 0.3048 0.3048)
			(layers "F.Cu" "F.Mask" "F.Paste")
			(net "M_DDR3_NODE1_MA11")
		)
		(pad "BL35" smd circle
			(at 0.783082 11.751564)
			(size 0.3048 0.3048)
			(layers "F.Cu" "F.Mask" "F.Paste")
			(net "M_DDR3_NODE1_MA7")
		)
		(pad "BL37" smd circle
			(at 1.897634 11.900916)
			(size 0.3048 0.3048)
			(layers "F.Cu" "F.Mask" "F.Paste")
			(net "M_DDR3_NODE1_MA3")
		)
		(pad "BL39" smd circle
			(at 2.786634 11.900916)
			(size 0.3048 0.3048)
			(layers "F.Cu" "F.Mask" "F.Paste")
			(net "M_DDR3_NODE1_MA1")
		)
		(pad "BL41" smd circle
			(at 3.937762 11.794744)
			(size 0.3048 0.3048)
			(layers "F.Cu" "F.Mask" "F.Paste")
			(net "M_DDR3_NODE1_BS1")
		)
		(pad "BL43" smd circle
			(at 4.60629 11.542522)
			(size 0.3048 0.3048)
			(layers "F.Cu" "F.Mask" "F.Paste")
			(net "M_DDR3_NODE1_BS0")
		)
		(pad "BL44" smd circle
			(at 5.285994 11.751564)
			(size 0.3048 0.3048)
			(layers "F.Cu" "F.Mask" "F.Paste")
			(net "M_DDR3_NODE1_WE_L")
		)
		(pad "BL46" smd circle
			(at 6.400546 11.900916)
			(size 0.3048 0.3048)
			(layers "F.Cu" "F.Mask" "F.Paste")
			(net "M_DDR3_NODE1_CKE0")
		)
		(pad "BL48" smd circle
			(at 7.289546 11.900916)
			(size 0.3048 0.3048)
			(layers "F.Cu" "F.Mask" "F.Paste")
			(net "M_DDR3_NODE1_ODT0")
		)
		(pad "BL50" smd circle
			(at 8.440674 11.794744)
			(size 0.3048 0.3048)
			(layers "F.Cu" "F.Mask" "F.Paste")
			(net "GND")
		)
		(pad "BL52" smd circle
			(at 9.109202 11.542522)
			(size 0.3048 0.3048)
			(layers "F.Cu" "F.Mask" "F.Paste")
			(net "GND")
		)
		(pad "BL53" smd circle
			(at 9.788906 11.751564)
			(size 0.3048 0.3048)
			(layers "F.Cu" "F.Mask" "F.Paste")
			(net "M1_DQ_NODE1_DQ38")
		)
		(pad "BL55" smd circle
			(at 10.903458 11.900916)
			(size 0.3048 0.3048)
			(layers "F.Cu" "F.Mask" "F.Paste")
			(net "M_DDR3_NODE1_DQS4P")
		)
		(pad "BL57" smd circle
			(at 11.792458 11.900916)
			(size 0.3048 0.3048)
			(layers "F.Cu" "F.Mask" "F.Paste")
			(net "M1_DQ_NODE1_DQ36")
		)
		(pad "BL59" smd circle
			(at 12.932664 11.751564)
			(size 0.3048 0.3048)
			(layers "F.Cu" "F.Mask" "F.Paste")
			(net "M1_DQ_NODE1_DQ37")
		)
		(pad "BL61" smd circle
			(at 13.612368 11.542522)
			(size 0.3048 0.3048)
			(layers "F.Cu" "F.Mask" "F.Paste")
			(net "GND")
		)
		(pad "BM1" smd circle
			(at -16.110966 12.298172)
			(size 0.4064 0.4064)
			(layers "F.Cu" "F.Mask" "F.Paste")
			(net "GND")
		)
		(pad "BM3" smd circle
			(at -15.298166 12.298172)
			(size 0.4064 0.4064)
			(layers "F.Cu" "F.Mask" "F.Paste")
			(net "TP_CPU_NODE1_RP0_PLLMON1")
		)
		(pad "BM5" smd circle
			(at -14.485366 12.298172)
			(size 0.4064 0.4064)
			(layers "F.Cu" "F.Mask" "F.Paste")
			(net "TP_CPU_NODE1_RP0_PLLMON0")
		)
		(pad "BM7" smd circle
			(at -13.405358 12.304522)
			(size 0.3048 0.3048)
			(layers "F.Cu" "F.Mask" "F.Paste")
			(net "TP_CPU_NODE1_RP0_PERN1")
		)
		(pad "BM9" smd circle
			(at -12.22248 12.247118)
			(size 0.3048 0.3048)
			(layers "F.Cu" "F.Mask" "F.Paste")
			(net "P2E_CPU_SATA_NODE1_RX_DN")
		)
		(pad "BM13" smd circle
			(at -10.110724 12.2428)
			(size 0.3048 0.3048)
			(layers "F.Cu" "F.Mask" "F.Paste")
			(net "M1_DQ_NODE1_DQ8")
		)
		(pad "BM16" smd circle
			(at -8.953246 12.304522)
			(size 0.3048 0.3048)
			(layers "F.Cu" "F.Mask" "F.Paste")
			(net "M_DDR3_NODE1_DQS1N")
		)
		(pad "BM18" smd circle
			(at -7.719568 12.247118)
			(size 0.3048 0.3048)
			(layers "F.Cu" "F.Mask" "F.Paste")
			(net "M1_DQ_NODE1_DQ11")
		)
		(pad "BM22" smd circle
			(at -5.607812 12.2428)
			(size 0.3048 0.3048)
			(layers "F.Cu" "F.Mask" "F.Paste")
			(net "M1_DQ_NODE1_DQ24")
		)
		(pad "BM25" smd circle
			(at -4.450334 12.304522)
			(size 0.3048 0.3048)
			(layers "F.Cu" "F.Mask" "F.Paste")
			(net "M_DDR3_NODE1_DQS3N")
		)
		(pad "BM27" smd circle
			(at -3.216656 12.247118)
			(size 0.3048 0.3048)
			(layers "F.Cu" "F.Mask" "F.Paste")
			(net "M1_DQ_NODE1_DQ27")
		)
		(pad "BM31" smd circle
			(at -1.1049 12.2428)
			(size 0.3048 0.3048)
			(layers "F.Cu" "F.Mask" "F.Paste")
			(net "M_DDR3_NODE1_MA14")
		)
		(pad "BM34" smd circle
			(at 0.052578 12.304522)
			(size 0.3048 0.3048)
			(layers "F.Cu" "F.Mask" "F.Paste")
			(net "M_DDR3_NODE1_MA9")
		)
		(pad "BM36" smd circle
			(at 1.286256 12.247118)
			(size 0.3048 0.3048)
			(layers "F.Cu" "F.Mask" "F.Paste")
			(net "PV_VDDR_NODE1")
		)
		(pad "BM40" smd circle
			(at 3.398012 12.2428)
			(size 0.3048 0.3048)
			(layers "F.Cu" "F.Mask" "F.Paste")
			(net "PV_VDDR_NODE1")
		)
		(pad "BM43" smd circle
			(at 4.55549 12.304522)
			(size 0.3048 0.3048)
			(layers "F.Cu" "F.Mask" "F.Paste")
			(net "PV_VDDR_NODE1")
		)
		(pad "BM45" smd circle
			(at 5.789168 12.247118)
			(size 0.3048 0.3048)
			(layers "F.Cu" "F.Mask" "F.Paste")
			(net "PV_VDDR_NODE1")
		)
		(pad "BM49" smd circle
			(at 7.900924 12.2428)
			(size 0.3048 0.3048)
			(layers "F.Cu" "F.Mask" "F.Paste")
			(net "PV_VDDR_NODE1")
		)
		(pad "BM52" smd circle
			(at 9.058402 12.304522)
			(size 0.3048 0.3048)
			(layers "F.Cu" "F.Mask" "F.Paste")
			(net "M1_DQ_NODE1_DQ32")
		)
		(pad "BM54" smd circle
			(at 10.29208 12.247118)
			(size 0.3048 0.3048)
			(layers "F.Cu" "F.Mask" "F.Paste")
			(net "M1_DQ_NODE1_DQ39")
		)
		(pad "BM58" smd circle
			(at 12.403836 12.2428)
			(size 0.3048 0.3048)
			(layers "F.Cu" "F.Mask" "F.Paste")
			(net "M1_DQ_NODE1_DQ33")
		)
		(pad "BM61" smd circle
			(at 13.612368 12.304522)
			(size 0.3048 0.3048)
			(layers "F.Cu" "F.Mask" "F.Paste")
			(net "GND")
		)
		(pad "BM62" smd circle
			(at 14.485366 12.298172)
			(size 0.4064 0.4064)
			(layers "F.Cu" "F.Mask" "F.Paste")
			(net "GND")
		)
		(pad "BM64" smd circle
			(at 15.298166 12.298172)
			(size 0.4064 0.4064)
			(layers "F.Cu" "F.Mask" "F.Paste")
			(net "GND")
		)
		(pad "BM66" smd circle
			(at 16.110966 12.298172)
			(size 0.4064 0.4064)
			(layers "F.Cu" "F.Mask" "F.Paste")
			(net "GND")
		)
		(pad "BN10" smd circle
			(at -11.617198 12.640818)
			(size 0.3048 0.3048)
			(layers "F.Cu" "F.Mask" "F.Paste")
			(net "P2E_CPU_SATA_NODE1_RX_DP")
		)
		(pad "BN12" smd circle
			(at -10.690606 12.63904)
			(size 0.3048 0.3048)
			(layers "F.Cu" "F.Mask" "F.Paste")
			(net "GND")
		)
		(pad "BN14" smd circle
			(at -9.623806 12.752324)
			(size 0.3048 0.3048)
			(layers "F.Cu" "F.Mask" "F.Paste")
			(net "M1_DQ_NODE1_DQ10")
		)
		(pad "BN17" smd circle
			(at -8.142986 12.805664)
			(size 0.3048 0.3048)
			(layers "F.Cu" "F.Mask" "F.Paste")
			(net "M_DDR3_NODE1_DQS1P")
		)
		(pad "BN19" smd circle
			(at -7.114286 12.640818)
			(size 0.3048 0.3048)
			(layers "F.Cu" "F.Mask" "F.Paste")
			(net "M1_DQ_NODE1_DQ13")
		)
		(pad "BN21" smd circle
			(at -6.187694 12.63904)
			(size 0.3048 0.3048)
			(layers "F.Cu" "F.Mask" "F.Paste")
			(net "GND")
		)
		(pad "BN23" smd circle
			(at -5.120894 12.752324)
			(size 0.3048 0.3048)
			(layers "F.Cu" "F.Mask" "F.Paste")
			(net "M1_DQ_NODE1_DQ26")
		)
		(pad "BN26" smd circle
			(at -3.640074 12.805664)
			(size 0.3048 0.3048)
			(layers "F.Cu" "F.Mask" "F.Paste")
			(net "M_DDR3_NODE1_DQS3P")
		)
		(pad "BN28" smd circle
			(at -2.611374 12.640818)
			(size 0.3048 0.3048)
			(layers "F.Cu" "F.Mask" "F.Paste")
			(net "M1_DQ_NODE1_DQ25")
		)
		(pad "BN30" smd circle
			(at -1.684782 12.63904)
			(size 0.3048 0.3048)
			(layers "F.Cu" "F.Mask" "F.Paste")
			(net "GND")
		)
		(pad "BN32" smd circle
			(at -0.617982 12.752324)
			(size 0.3048 0.3048)
			(layers "F.Cu" "F.Mask" "F.Paste")
			(net "M_DDR3_NODE1_BS2")
		)
		(pad "BN35" smd circle
			(at 0.862838 12.805664)
			(size 0.3048 0.3048)
			(layers "F.Cu" "F.Mask" "F.Paste")
			(net "M_DDR3_NODE1_MA8")
		)
		(pad "BN37" smd circle
			(at 1.891538 12.640818)
			(size 0.3048 0.3048)
			(layers "F.Cu" "F.Mask" "F.Paste")
			(net "M_DDR3_NODE1_MA5")
		)
		(pad "BN39" smd circle
			(at 2.81813 12.63904)
			(size 0.3048 0.3048)
			(layers "F.Cu" "F.Mask" "F.Paste")
			(net "M_DDR3_NODE1_MA4")
		)
		(pad "BN41" smd circle
			(at 3.88493 12.752324)
			(size 0.3048 0.3048)
			(layers "F.Cu" "F.Mask" "F.Paste")
			(net "M_DDR3_NODE1_MA10")
		)
		(pad "BN44" smd circle
			(at 5.36575 12.805664)
			(size 0.3048 0.3048)
			(layers "F.Cu" "F.Mask" "F.Paste")
			(net "M_DDR3_NODE1_CS0_L")
		)
		(pad "BN46" smd circle
			(at 6.39445 12.640818)
			(size 0.3048 0.3048)
			(layers "F.Cu" "F.Mask" "F.Paste")
			(net "M_DDR3_NODE1_CAS_L")
		)
		(pad "BN48" smd circle
			(at 7.321042 12.63904)
			(size 0.3048 0.3048)
			(layers "F.Cu" "F.Mask" "F.Paste")
			(net "M_DDR3_NODE1_MA13")
		)
		(pad "BN50" smd circle
			(at 8.387842 12.752324)
			(size 0.3048 0.3048)
			(layers "F.Cu" "F.Mask" "F.Paste")
			(net "GND")
		)
		(pad "BN53" smd circle
			(at 9.868662 12.805664)
			(size 0.3048 0.3048)
			(layers "F.Cu" "F.Mask" "F.Paste")
			(net "M1_DQ_NODE1_DQ34")
		)
		(pad "BN55" smd circle
			(at 10.897362 12.640818)
			(size 0.3048 0.3048)
			(layers "F.Cu" "F.Mask" "F.Paste")
			(net "M_DDR3_NODE1_DQS4N")
		)
		(pad "BN57" smd circle
			(at 11.823954 12.63904)
			(size 0.3048 0.3048)
			(layers "F.Cu" "F.Mask" "F.Paste")
			(net "M1_DQ_NODE1_DQ35")
		)
		(pad "BP1" smd circle
			(at -16.110966 13.110972)
			(size 0.4064 0.4064)
			(layers "F.Cu" "F.Mask" "F.Paste")
			(net "GND")
		)
		(pad "BP3" smd circle
			(at -15.298166 13.110972)
			(size 0.4064 0.4064)
			(layers "F.Cu" "F.Mask" "F.Paste")
			(net "GND")
		)
		(pad "BP5" smd circle
			(at -14.485366 13.110972)
			(size 0.4064 0.4064)
			(layers "F.Cu" "F.Mask" "F.Paste")
			(net "GND")
		)
		(pad "BP6" smd circle
			(at -13.672566 13.110972)
			(size 0.4064 0.4064)
			(layers "F.Cu" "F.Mask" "F.Paste")
			(net "GND")
		)
	)
)
